# S9S_MB_2U (Grand Teton) — schematic netlist excerpt (pin names and nets, part order shuffled) for the footprints in the layout excerpt that follows; sources: Cadence DE-HDL packaged netlist, KiCad conversion of 03242023_DA0F0TMBIJ0_F0T_Motherboard_J_brd_V01_OCP.brd

R2796  Q_RES  33.2 1% CHIP  pkg 0402LF  page 245 : A = FM_PDB_BUF_EN_R ; B = FM_MB_PDB_SMB9_R_EN
PR3999  Q_RES  24.3K 1% CHIP  pkg 0402LF  page 242 : A = P12V_SCM_ISET ; B = GND

(kicad_pcb
	(version 20260206)
	(generator "pcbnew")
	(generator_version "10.0")
	(general
		(thickness 1.6)
		(legacy_teardrops no)
	)
	(paper "A4")
	(title_block
		(title "03242023_DA0F0TMBIJ0_F0T_Motherboard_J_brd_V01_OCP.brd")
		(comment 1 "Grand Teton / footprints 707-708 of 6105")
	)
	(layers
		(0 "F.Cu" signal "TOP")
		(4 "In1.Cu" signal "GND")
		(6 "In2.Cu" signal "IN1")
		(8 "In3.Cu" signal "GND1")
		(10 "In4.Cu" signal "IN2")
		(12 "In5.Cu" signal "GND2")
		(14 "In6.Cu" signal "IN3")
		(16 "In7.Cu" signal "GND3")
		(18 "In8.Cu" signal "VCC")
		(20 "In9.Cu" signal "VCC1")
		(22 "In10.Cu" signal "GND4")
		(24 "In11.Cu" signal "IN4")
		(26 "In12.Cu" signal "GND5")
		(28 "In13.Cu" signal "IN5")
		(30 "In14.Cu" signal "GND6")
		(32 "In15.Cu" signal "IN6")
		(34 "In16.Cu" signal "GND7")
		(2 "B.Cu" signal "BOTTOM")
		(9 "F.Adhes" user "F.Adhesive")
		(11 "B.Adhes" user "B.Adhesive")
		(13 "F.Paste" user "Package Geometry/Pastemask Top")
		(15 "B.Paste" user "Package Geometry/Pastemask Bottom")
		(5 "F.SilkS" user "Ref Des/Silkscreen Top")
		(7 "B.SilkS" user "Ref Des/Silkscreen Bottom")
		(1 "F.Mask" user "Board Geometry/Soldermask Top")
		(3 "B.Mask" user "Board Geometry/Soldermask Bottom")
		(17 "Dwgs.User" user "User.Drawings")
		(19 "Cmts.User" user "User.Comments")
		(21 "Eco1.User" user "User.Eco1")
		(23 "Eco2.User" user "User.Eco2")
		(25 "Edge.Cuts" user "Board Geometry/Outline")
		(27 "Margin" user)
		(31 "F.CrtYd" user "Package Geometry/Place Bound Top")
		(29 "B.CrtYd" user "Package Geometry/Place Bound Bottom")
		(35 "F.Fab" user "Ref Des/Assembly Top")
		(33 "B.Fab" user "Ref Des/Assembly Bottom")
	)
	(footprint ""
		(layer "F.Cu")
		(at 178.044602 -32.950912 90)
		(property "Reference" "PR3999"
			(at 0 0 90)
			(layer "F.SilkS")
			(hide yes)
			(effects
				(font
					(size 1.27 1.27)
				)
			)
		)
		(property "Value" ""
			(at 0 0 90)
			(layer "F.Fab")
			(effects
				(font
					(size 1.27 1.27)
				)
			)
		)
		(duplicate_pad_numbers_are_jumpers no)
		(fp_line
			(start 0.7874 -0.4064)
			(end 0.7874 0.4064)
			(stroke
				(width 0.1524)
				(type default)
			)
			(layer "F.SilkS")
		)
		(fp_line
			(start -0.7874 -0.4064)
			(end 0.7874 -0.4064)
			(stroke
				(width 0.1524)
				(type default)
			)
			(layer "F.SilkS")
		)
		(fp_line
			(start 0.7874 0.4064)
			(end -0.7874 0.4064)
			(stroke
				(width 0.1524)
				(type default)
			)
			(layer "F.SilkS")
		)
		(fp_line
			(start -0.7874 0.4064)
			(end -0.7874 -0.4064)
			(stroke
				(width 0.1524)
				(type default)
			)
			(layer "F.SilkS")
		)
		(fp_line
			(start -0.12065 -0.305054)
			(end -0.12065 -0.2794)
			(stroke
				(width 0.1)
				(type default)
			)
			(layer "F.Fab")
		)
		(fp_line
			(start -0.67945 -0.305054)
			(end -0.12065 -0.305054)
			(stroke
				(width 0.1)
				(type default)
			)
			(layer "F.Fab")
		)
		(fp_line
			(start 0.67945 -0.3048)
			(end 0.67945 0.3048)
			(stroke
				(width 0.1)
				(type default)
			)
			(layer "F.Fab")
		)
		(fp_line
			(start 0.12065 -0.3048)
			(end 0.67945 -0.3048)
			(stroke
				(width 0.1)
				(type default)
			)
			(layer "F.Fab")
		)
		(fp_line
			(start 0.12065 -0.2794)
			(end 0.12065 -0.3048)
			(stroke
				(width 0.1)
				(type default)
			)
			(layer "F.Fab")
		)
		(fp_line
			(start -0.12065 -0.2794)
			(end 0.12065 -0.2794)
			(stroke
				(width 0.1)
				(type default)
			)
			(layer "F.Fab")
		)
		(fp_line
			(start 0.120396 0.2794)
			(end -0.12065 0.2794)
			(stroke
				(width 0.1)
				(type default)
			)
			(layer "F.Fab")
		)
		(fp_line
			(start -0.12065 0.2794)
			(end -0.12065 0.3048)
			(stroke
				(width 0.1)
				(type default)
			)
			(layer "F.Fab")
		)
		(fp_line
			(start 0.67945 0.3048)
			(end 0.120396 0.3048)
			(stroke
				(width 0.1)
				(type default)
			)
			(layer "F.Fab")
		)
		(fp_line
			(start 0.120396 0.3048)
			(end 0.120396 0.2794)
			(stroke
				(width 0.1)
				(type default)
			)
			(layer "F.Fab")
		)
		(fp_line
			(start -0.12065 0.3048)
			(end -0.67945 0.3048)
			(stroke
				(width 0.1)
				(type default)
			)
			(layer "F.Fab")
		)
		(fp_line
			(start -0.67945 0.3048)
			(end -0.67945 -0.305054)
			(stroke
				(width 0.1)
				(type default)
			)
			(layer "F.Fab")
		)
		(pad "1" smd circle
			(at -0.40005 0 90)
			(size 0 0)
			(layers "F.Cu" "F.Mask" "F.Paste")
			(net "P12V_SCM_ISET")
		)
		(pad "2" smd circle
			(at 0.40005 0 90)
			(size 0 0)
			(layers "F.Cu" "F.Mask" "F.Paste")
			(net "GND")
		)
	)
	(footprint ""
		(layer "F.Cu")
		(at 181.135782 -426.8216 180)
		(property "Reference" "R2796"
			(at 0 0 180)
			(layer "F.SilkS")
			(hide yes)
			(effects
				(font
					(size 1.27 1.27)
				)
			)
		)
		(property "Value" ""
			(at 0 0 180)
			(layer "F.Fab")
			(effects
				(font
					(size 1.27 1.27)
				)
			)
		)
		(duplicate_pad_numbers_are_jumpers no)
		(fp_line
			(start 0.7874 0.4064)
			(end -0.7874 0.4064)
			(stroke
				(width 0.1524)
				(type default)
			)
			(layer "F.SilkS")
		)
		(fp_line
			(start 0.7874 -0.4064)
			(end 0.7874 0.4064)
			(stroke
				(width 0.1524)
				(type default)
			)
			(layer "F.SilkS")
		)
		(fp_line
			(start -0.7874 0.4064)
			(end -0.7874 -0.4064)
			(stroke
				(width 0.1524)
				(type default)
			)
			(layer "F.SilkS")
		)
		(fp_line
			(start -0.7874 -0.4064)
			(end 0.7874 -0.4064)
			(stroke
				(width 0.1524)
				(type default)
			)
			(layer "F.SilkS")
		)
		(fp_line
			(start 0.67945 0.3048)
			(end 0.120396 0.3048)
			(stroke
				(width 0.1)
				(type default)
			)
			(layer "F.Fab")
		)
		(fp_line
			(start 0.67945 -0.3048)
			(end 0.67945 0.3048)
			(stroke
				(width 0.1)
				(type default)
			)
			(layer "F.Fab")
		)
		(fp_line
			(start 0.12065 -0.2794)
			(end 0.12065 -0.3048)
			(stroke
				(width 0.1)
				(type default)
			)
			(layer "F.Fab")
		)
		(fp_line
			(start 0.12065 -0.3048)
			(end 0.67945 -0.3048)
			(stroke
				(width 0.1)
				(type default)
			)
			(layer "F.Fab")
		)
		(fp_line
			(start 0.120396 0.3048)
			(end 0.120396 0.2794)
			(stroke
				(width 0.1)
				(type default)
			)
			(layer "F.Fab")
		)
		(fp_line
			(start 0.120396 0.2794)
			(end -0.12065 0.2794)
			(stroke
				(width 0.1)
				(type default)
			)
			(layer "F.Fab")
		)
		(fp_line
			(start -0.12065 0.3048)
			(end -0.67945 0.3048)
			(stroke
				(width 0.1)
				(type default)
			)
			(layer "F.Fab")
		)
		(fp_line
			(start -0.12065 0.2794)
			(end -0.12065 0.3048)
			(stroke
				(width 0.1)
				(type default)
			)
			(layer "F.Fab")
		)
		(fp_line
			(start -0.12065 -0.2794)
			(end 0.12065 -0.2794)
			(stroke
				(width 0.1)
				(type default)
			)
			(layer "F.Fab")
		)
		(fp_line
			(start -0.12065 -0.305054)
			(end -0.12065 -0.2794)
			(stroke
				(width 0.1)
				(type default)
			)
			(layer "F.Fab")
		)
		(fp_line
			(start -0.67945 0.3048)
			(end -0.67945 -0.305054)
			(stroke
				(width 0.1)
				(type default)
			)
			(layer "F.Fab")
		)
		(fp_line
			(start -0.67945 -0.305054)
			(end -0.12065 -0.305054)
			(stroke
				(width 0.1)
				(type default)
			)
			(layer "F.Fab")
		)
		(pad "1" smd circle
			(at -0.40005 0 180)
			(size 0 0)
			(layers "F.Cu" "F.Mask" "F.Paste")
			(net "FM_PDB_BUF_EN_R")
		)
		(pad "2" smd circle
			(at 0.40005 0 180)
			(size 0 0)
			(layers "F.Cu" "F.Mask" "F.Paste")
			(net "FM_MB_PDB_SMB9_R_EN")
		)
	)
)
